(kicad_pcb
	(version 20260206)
	(generator "pcbnew")
	(generator_version "10.0")
	(general
		(thickness 1.6)
		(legacy_teardrops no)
	)
	(paper "A4")
	(title_block
		(title "9054_F0T_PDB_BD_GPU_F_V04_1213_1550_OCP.brd")
		(comment 1 "Grand Teton / footprints 15-19 of 608")
	)
	(layers
		(0 "F.Cu" signal "TOP")
		(4 "In1.Cu" signal "GND")
		(6 "In2.Cu" signal "IN1")
		(8 "In3.Cu" signal "GND1")
		(10 "In4.Cu" signal "VCC")
		(12 "In5.Cu" signal "VCC1")
		(14 "In6.Cu" signal "GND2")
		(16 "In7.Cu" signal "IN2")
		(18 "In8.Cu" signal "GND3")
		(2 "B.Cu" signal "BOTTOM")
		(9 "F.Adhes" user "F.Adhesive")
		(11 "B.Adhes" user "B.Adhesive")
		(13 "F.Paste" user "Package Geometry/Pastemask Top")
		(15 "B.Paste" user "Package Geometry/Pastemask Bottom")
		(5 "F.SilkS" user "Ref Des/Silkscreen Top")
		(7 "B.SilkS" user "Ref Des/Silkscreen Bottom")
		(1 "F.Mask" user "Board Geometry/Soldermask Top")
		(3 "B.Mask" user "Board Geometry/Soldermask Bottom")
		(17 "Dwgs.User" user "User.Drawings")
		(19 "Cmts.User" user "User.Comments")
		(21 "Eco1.User" user "User.Eco1")
		(23 "Eco2.User" user "User.Eco2")
		(25 "Edge.Cuts" user "Board Geometry/Outline")
		(27 "Margin" user)
		(31 "F.CrtYd" user "Package Geometry/Place Bound Top")
		(29 "B.CrtYd" user "Package Geometry/Place Bound Bottom")
		(35 "F.Fab" user "Ref Des/Assembly Top")
		(33 "B.Fab" user "Ref Des/Assembly Bottom")
	)
	(footprint ""
		(layer "F.Cu")
		(at 449.326 -31.623 180)
		(property "Reference" "R20"
			(at 0 0 180)
			(layer "F.SilkS")
			(hide yes)
			(effects
				(font
					(size 1.27 1.27)
				)
			)
		)
		(property "Value" ""
			(at 0 0 180)
			(layer "F.Fab")
			(effects
				(font
					(size 1.27 1.27)
				)
			)
		)
		(duplicate_pad_numbers_are_jumpers no)
		(fp_line
			(start 0.7874 0.4064)
			(end -0.7874 0.4064)
			(stroke
				(width 0.1524)
				(type default)
			)
			(layer "F.SilkS")
		)
		(fp_line
			(start 0.7874 -0.4064)
			(end 0.7874 0.4064)
			(stroke
				(width 0.1524)
				(type default)
			)
			(layer "F.SilkS")
		)
		(fp_line
			(start -0.7874 0.4064)
			(end -0.7874 -0.4064)
			(stroke
				(width 0.1524)
				(type default)
			)
			(layer "F.SilkS")
		)
		(fp_line
			(start -0.7874 -0.4064)
			(end 0.7874 -0.4064)
			(stroke
				(width 0.1524)
				(type default)
			)
			(layer "F.SilkS")
		)
		(fp_line
			(start 0.67945 0.3048)
			(end 0.120396 0.3048)
			(stroke
				(width 0.1)
				(type default)
			)
			(layer "F.Fab")
		)
		(fp_line
			(start 0.67945 -0.3048)
			(end 0.67945 0.3048)
			(stroke
				(width 0.1)
				(type default)
			)
			(layer "F.Fab")
		)
		(fp_line
			(start 0.12065 -0.2794)
			(end 0.12065 -0.3048)
			(stroke
				(width 0.1)
				(type default)
			)
			(layer "F.Fab")
		)
		(fp_line
			(start 0.12065 -0.3048)
			(end 0.67945 -0.3048)
			(stroke
				(width 0.1)
				(type default)
			)
			(layer "F.Fab")
		)
		(fp_line
			(start 0.120396 0.3048)
			(end 0.120396 0.2794)
			(stroke
				(width 0.1)
				(type default)
			)
			(layer "F.Fab")
		)
		(fp_line
			(start 0.120396 0.2794)
			(end -0.12065 0.2794)
			(stroke
				(width 0.1)
				(type default)
			)
			(layer "F.Fab")
		)
		(fp_line
			(start -0.12065 0.3048)
			(end -0.67945 0.3048)
			(stroke
				(width 0.1)
				(type default)
			)
			(layer "F.Fab")
		)
		(fp_line
			(start -0.12065 0.2794)
			(end -0.12065 0.3048)
			(stroke
				(width 0.1)
				(type default)
			)
			(layer "F.Fab")
		)
		(fp_line
			(start -0.12065 -0.2794)
			(end 0.12065 -0.2794)
			(stroke
				(width 0.1)
				(type default)
			)
			(layer "F.Fab")
		)
		(fp_line
			(start -0.12065 -0.305054)
			(end -0.12065 -0.2794)
			(stroke
				(width 0.1)
				(type default)
			)
			(layer "F.Fab")
		)
		(fp_line
			(start -0.67945 0.3048)
			(end -0.67945 -0.305054)
			(stroke
				(width 0.1)
				(type default)
			)
			(layer "F.Fab")
		)
		(fp_line
			(start -0.67945 -0.305054)
			(end -0.12065 -0.305054)
			(stroke
				(width 0.1)
				(type default)
			)
			(layer "F.Fab")
		)
		(pad "1" smd circle
			(at -0.40005 0 180)
			(size 0 0)
			(layers "F.Cu" "F.Mask" "F.Paste")
			(net "SMB_PDB_MISC_SCL_R1")
		)
		(pad "2" smd circle
			(at 0.40005 0 180)
			(size 0 0)
			(layers "F.Cu" "F.Mask" "F.Paste")
			(net "SMB_FAN_MUX_SCL")
		)
	)
	(footprint ""
		(layer "F.Cu")
		(at 42.36339 -35.053778 90)
		(property "Reference" "PQ16"
			(at 2.538222 6.71068 90)
			(unlocked yes)
			(layer "F.SilkS")
			(effects
				(font
					(size 0.7874 0.5842)
					(thickness 0.1524)
				)
				(justify left)
			)
		)
		(property "Value" ""
			(at 0 0 90)
			(layer "F.Fab")
			(effects
				(font
					(size 1.27 1.27)
				)
			)
		)
		(duplicate_pad_numbers_are_jumpers no)
		(fp_line
			(start 7.649972 -4.99999)
			(end 7.630414 -4.99999)
			(stroke
				(width 0.1524)
				(type default)
			)
			(layer "F.SilkS")
		)
		(fp_line
			(start 5.115814 -4.99999)
			(end -7.649972 -4.99999)
			(stroke
				(width 0.1524)
				(type default)
			)
			(layer "F.SilkS")
		)
		(fp_line
			(start -7.649972 -4.99999)
			(end -7.649972 -3.3274)
			(stroke
				(width 0.1524)
				(type default)
			)
			(layer "F.SilkS")
		)
		(fp_line
			(start -7.649972 -1.7526)
			(end -7.649972 1.7526)
			(stroke
				(width 0.1524)
				(type default)
			)
			(layer "F.SilkS")
		)
		(fp_line
			(start -7.649972 3.3274)
			(end -7.649972 4.99999)
			(stroke
				(width 0.1524)
				(type default)
			)
			(layer "F.SilkS")
		)
		(fp_line
			(start 7.649972 4.99999)
			(end 7.649972 -4.99999)
			(stroke
				(width 0.1524)
				(type default)
			)
			(layer "F.SilkS")
		)
		(fp_line
			(start 7.630414 4.99999)
			(end 7.649972 4.99999)
			(stroke
				(width 0.1524)
				(type default)
			)
			(layer "F.SilkS")
		)
		(fp_line
			(start -7.649972 4.99999)
			(end 5.115814 4.99999)
			(stroke
				(width 0.1524)
				(type default)
			)
			(layer "F.SilkS")
		)
		(fp_line
			(start 7.649972 -4.99999)
			(end -7.649972 -4.99999)
			(stroke
				(width 0.1)
				(type default)
			)
			(layer "F.Fab")
		)
		(fp_line
			(start -7.649972 -4.99999)
			(end -7.649972 4.99999)
			(stroke
				(width 0.1)
				(type default)
			)
			(layer "F.Fab")
		)
		(fp_line
			(start 7.649972 4.99999)
			(end 7.649972 -4.99999)
			(stroke
				(width 0.1)
				(type default)
			)
			(layer "F.Fab")
		)
		(fp_line
			(start -7.649972 4.99999)
			(end 7.649972 4.99999)
			(stroke
				(width 0.1)
				(type default)
			)
			(layer "F.Fab")
		)
		(pad "D" smd circle
			(at 2.15011 0 90)
			(size 0 0)
			(layers "F.Cu" "F.Mask" "F.Paste")
			(net "P52V_HS2")
		)
		(pad "G" smd rect
			(at -7.050024 -2.54)
			(size 1.3208 3.0988)
			(layers "F.Cu" "F.Mask" "F.Paste")
			(net "P52V_HS2_EN_DISCHARGE_N")
		)
		(pad "S" smd rect
			(at -7.050024 2.54)
			(size 1.3208 3.0988)
			(layers "F.Cu" "F.Mask" "F.Paste")
			(net "P52V_HS2_EN_DISCHARGE_VBE_R")
		)
		(zone
			(layer "F.Cu")
			(hatch none 0.5)
			(connect_pads
				(clearance 0)
			)
			(min_thickness 0.25)
			(keepout
				(tracks not_allowed)
				(vias allowed)
				(pads allowed)
				(copperpour not_allowed)
				(footprints allowed)
			)
			(placement
				(enabled no)
				(sheetname "")
			)
			(fill
				(thermal_gap 0.5)
				(thermal_bridge_width 0.5)
				(island_removal_mode 0)
			)
			(polygon
				(pts
					(xy 37.38499 -40.235378) (xy 37.38499 -27.408378) (xy 39.11219 -27.408378) (xy 39.11219 -29.618178)
					(xy 40.53459 -29.618178) (xy 40.53459 -27.408378) (xy 44.19219 -27.408378) (xy 44.19219 -29.618178)
					(xy 45.61459 -29.618178) (xy 45.61459 -27.408378) (xy 47.34179 -27.408378) (xy 47.34179 -40.235378)
					(xy 46.17339 -40.235378) (xy 46.17339 -34.037778) (xy 38.55339 -34.037778) (xy 38.55339 -40.235378)
				)
			)
		)
	)
	(footprint ""
		(layer "F.Cu")
		(at 381.4064 -31.242 90)
		(property "Reference" "PD8"
			(at -4.7752 -3.749548 90)
			(unlocked yes)
			(layer "F.SilkS")
			(effects
				(font
					(size 0.7874 0.5842)
					(thickness 0.1524)
				)
				(justify left)
			)
		)
		(property "Value" ""
			(at 0 0 90)
			(layer "F.Fab")
			(effects
				(font
					(size 1.27 1.27)
				)
			)
		)
		(duplicate_pad_numbers_are_jumpers no)
		(fp_line
			(start 4.826 -3.109976)
			(end 4.826 0)
			(stroke
				(width 0.1524)
				(type default)
			)
			(layer "F.SilkS")
		)
		(fp_line
			(start 4.8133 -3.109976)
			(end 5.3467 -3.109976)
			(stroke
				(width 0.1524)
				(type default)
			)
			(layer "F.SilkS")
		)
		(fp_line
			(start -4.826 -3.109976)
			(end 4.826 -3.109976)
			(stroke
				(width 0.1524)
				(type default)
			)
			(layer "F.SilkS")
		)
		(fp_line
			(start -1.016 -1.016)
			(end -1.016 1.016)
			(stroke
				(width 0.1524)
				(type default)
			)
			(layer "F.SilkS")
		)
		(fp_line
			(start 5.334 0)
			(end 5.334 -3.109976)
			(stroke
				(width 0.1524)
				(type default)
			)
			(layer "F.SilkS")
		)
		(fp_line
			(start 4.826 0)
			(end 4.826 3.109976)
			(stroke
				(width 0.1524)
				(type default)
			)
			(layer "F.SilkS")
		)
		(fp_line
			(start 1.143 0)
			(end -1.016 -1.016)
			(stroke
				(width 0.1524)
				(type default)
			)
			(layer "F.SilkS")
		)
		(fp_line
			(start 1.143 0)
			(end 1.8034 0)
			(stroke
				(width 0.1524)
				(type default)
			)
			(layer "F.SilkS")
		)
		(fp_line
			(start -1.0922 0)
			(end -1.7018 0)
			(stroke
				(width 0.1524)
				(type default)
			)
			(layer "F.SilkS")
		)
		(fp_line
			(start -4.826 0)
			(end -4.826 -3.109976)
			(stroke
				(width 0.1524)
				(type default)
			)
			(layer "F.SilkS")
		)
		(fp_line
			(start -1.016 1.016)
			(end 1.016 0)
			(stroke
				(width 0.1524)
				(type default)
			)
			(layer "F.SilkS")
		)
		(fp_line
			(start 1.143 1.397)
			(end 1.143 -1.397)
			(stroke
				(width 0.1524)
				(type default)
			)
			(layer "F.SilkS")
		)
		(fp_line
			(start 5.334 3.109976)
			(end 5.334 0)
			(stroke
				(width 0.1524)
				(type default)
			)
			(layer "F.SilkS")
		)
		(fp_line
			(start 5.334 3.109976)
			(end 4.8133 3.109976)
			(stroke
				(width 0.1524)
				(type default)
			)
			(layer "F.SilkS")
		)
		(fp_line
			(start 5.207 3.109976)
			(end 5.207 -3.109976)
			(stroke
				(width 0.1524)
				(type default)
			)
			(layer "F.SilkS")
		)
		(fp_line
			(start 5.1308 3.109976)
			(end 5.1308 -3.109976)
			(stroke
				(width 0.1524)
				(type default)
			)
			(layer "F.SilkS")
		)
		(fp_line
			(start 5.0292 3.109976)
			(end 5.0292 -3.109976)
			(stroke
				(width 0.1524)
				(type default)
			)
			(layer "F.SilkS")
		)
		(fp_line
			(start 4.9276 3.109976)
			(end 4.9276 -3.109976)
			(stroke
				(width 0.1524)
				(type default)
			)
			(layer "F.SilkS")
		)
		(fp_line
			(start 4.826 3.109976)
			(end -4.826 3.109976)
			(stroke
				(width 0.1524)
				(type default)
			)
			(layer "F.SilkS")
		)
		(fp_line
			(start -4.826 3.109976)
			(end -4.826 0)
			(stroke
				(width 0.1524)
				(type default)
			)
			(layer "F.SilkS")
		)
		(fp_line
			(start 3.554984 -3.109976)
			(end 3.554984 3.109976)
			(stroke
				(width 0.1)
				(type default)
			)
			(layer "F.Fab")
		)
		(fp_line
			(start -3.554984 -3.109976)
			(end 3.554984 -3.109976)
			(stroke
				(width 0.1)
				(type default)
			)
			(layer "F.Fab")
		)
		(fp_line
			(start -1.016 -1.016)
			(end -1.016 1.016)
			(stroke
				(width 0.1)
				(type default)
			)
			(layer "F.Fab")
		)
		(fp_line
			(start 1.143 0)
			(end -1.016 -1.016)
			(stroke
				(width 0.1)
				(type default)
			)
			(layer "F.Fab")
		)
		(fp_line
			(start 1.143 0)
			(end 1.8034 0)
			(stroke
				(width 0.1)
				(type default)
			)
			(layer "F.Fab")
		)
		(fp_line
			(start -1.0922 0)
			(end -1.7018 0)
			(stroke
				(width 0.1)
				(type default)
			)
			(layer "F.Fab")
		)
		(fp_line
			(start -1.016 1.016)
			(end 1.016 0)
			(stroke
				(width 0.1)
				(type default)
			)
			(layer "F.Fab")
		)
		(fp_line
			(start 1.143 1.397)
			(end 1.143 -1.397)
			(stroke
				(width 0.1)
				(type default)
			)
			(layer "F.Fab")
		)
		(fp_line
			(start 3.554984 3.109976)
			(end -3.554984 3.109976)
			(stroke
				(width 0.1)
				(type default)
			)
			(layer "F.Fab")
		)
		(fp_line
			(start -3.554984 3.109976)
			(end -3.554984 -3.109976)
			(stroke
				(width 0.1)
				(type default)
			)
			(layer "F.Fab")
		)
		(fp_text user "+"
			(at -4.5466 0.19685 270)
			(unlocked yes)
			(layer "F.SilkS")
			(effects
				(font
					(size 1.905 1.4224)
					(thickness 0.1524)
				)
				(justify left)
			)
		)
		(fp_text user "-"
			(at 6.6802 0.22225 270)
			(unlocked yes)
			(layer "F.SilkS")
			(effects
				(font
					(size 1.905 1.4224)
					(thickness 0.1524)
				)
				(justify left)
			)
		)
		(fp_text user "+"
			(at -4.5466 0.19685 270)
			(unlocked yes)
			(layer "F.Fab")
			(effects
				(font
					(size 1.905 1.4224)
					(thickness 0.1524)
				)
				(justify left)
			)
		)
		(fp_text user "-"
			(at 6.6802 0.22225 270)
			(unlocked yes)
			(layer "F.Fab")
			(effects
				(font
					(size 1.905 1.4224)
					(thickness 0.1524)
				)
				(justify left)
			)
		)
		(pad "A" smd rect
			(at -3.400044 0 270)
			(size 2.5146 3.302)
			(layers "F.Cu" "F.Mask" "F.Paste")
			(net "GND")
		)
		(pad "C" smd rect
			(at 3.400044 0 270)
			(size 2.5146 3.302)
			(layers "F.Cu" "F.Mask" "F.Paste")
			(net "P52V_HS1")
		)
	)
	(footprint ""
		(layer "F.Cu")
		(at 302.4124 -71.755 180)
		(property "Reference" "PR6956"
			(at 0 0 180)
			(layer "F.SilkS")
			(hide yes)
			(effects
				(font
					(size 1.27 1.27)
				)
			)
		)
		(property "Value" ""
			(at 0 0 180)
			(layer "F.Fab")
			(effects
				(font
					(size 1.27 1.27)
				)
			)
		)
		(duplicate_pad_numbers_are_jumpers no)
		(fp_line
			(start 1.2954 0.5842)
			(end -1.2954 0.5842)
			(stroke
				(width 0.1524)
				(type default)
			)
			(layer "F.SilkS")
		)
		(fp_line
			(start 1.2954 -0.5842)
			(end 1.2954 0.5842)
			(stroke
				(width 0.1524)
				(type default)
			)
			(layer "F.SilkS")
		)
		(fp_line
			(start -1.2954 0.5842)
			(end -1.2954 -0.5842)
			(stroke
				(width 0.1524)
				(type default)
			)
			(layer "F.SilkS")
		)
		(fp_line
			(start -1.2954 -0.5842)
			(end 1.2954 -0.5842)
			(stroke
				(width 0.1524)
				(type default)
			)
			(layer "F.SilkS")
		)
		(fp_line
			(start 1.1938 0.4064)
			(end 0.8636 0.4064)
			(stroke
				(width 0.1)
				(type default)
			)
			(layer "F.Fab")
		)
		(fp_line
			(start 1.1938 -0.406654)
			(end 1.1938 0.4064)
			(stroke
				(width 0.1)
				(type default)
			)
			(layer "F.Fab")
		)
		(fp_line
			(start 0.8636 0.4572)
			(end -0.8636 0.4572)
			(stroke
				(width 0.1)
				(type default)
			)
			(layer "F.Fab")
		)
		(fp_line
			(start 0.8636 0.4064)
			(end 0.8636 0.4572)
			(stroke
				(width 0.1)
				(type default)
			)
			(layer "F.Fab")
		)
		(fp_line
			(start 0.8636 -0.406654)
			(end 1.1938 -0.406654)
			(stroke
				(width 0.1)
				(type default)
			)
			(layer "F.Fab")
		)
		(fp_line
			(start 0.8636 -0.4572)
			(end 0.8636 -0.406654)
			(stroke
				(width 0.1)
				(type default)
			)
			(layer "F.Fab")
		)
		(fp_line
			(start -0.8636 0.4572)
			(end -0.8636 0.4318)
			(stroke
				(width 0.1)
				(type default)
			)
			(layer "F.Fab")
		)
		(fp_line
			(start -0.8636 0.4318)
			(end -0.8636 0.4064)
			(stroke
				(width 0.1)
				(type default)
			)
			(layer "F.Fab")
		)
		(fp_line
			(start -0.8636 0.4064)
			(end -1.1938 0.4064)
			(stroke
				(width 0.1)
				(type default)
			)
			(layer "F.Fab")
		)
		(fp_line
			(start -0.8636 -0.406654)
			(end -0.8636 -0.4572)
			(stroke
				(width 0.1)
				(type default)
			)
			(layer "F.Fab")
		)
		(fp_line
			(start -0.8636 -0.4572)
			(end 0.8636 -0.4572)
			(stroke
				(width 0.1)
				(type default)
			)
			(layer "F.Fab")
		)
		(fp_line
			(start -1.1938 0.4064)
			(end -1.1938 -0.406654)
			(stroke
				(width 0.1)
				(type default)
			)
			(layer "F.Fab")
		)
		(fp_line
			(start -1.1938 -0.406654)
			(end -0.8636 -0.406654)
			(stroke
				(width 0.1)
				(type default)
			)
			(layer "F.Fab")
		)
		(pad "1" smd rect
			(at -0.7366 0 90)
			(size 0.7112 0.8128)
			(layers "F.Cu" "F.Mask" "F.Paste")
			(net "P52V_HS_4287_S1P")
		)
		(pad "2" smd rect
			(at 0.7366 0 90)
			(size 0.7112 0.8128)
			(layers "F.Cu" "F.Mask" "F.Paste")
			(net "P52V_HS1_SENSE_P_R1")
		)
	)
	(footprint ""
		(layer "F.Cu")
		(at 334.631284 -16.51 -90)
		(property "Reference" "PR478"
			(at 0 0 270)
			(layer "F.SilkS")
			(hide yes)
			(effects
				(font
					(size 1.27 1.27)
				)
			)
		)
		(property "Value" ""
			(at 0 0 270)
			(layer "F.Fab")
			(effects
				(font
					(size 1.27 1.27)
				)
			)
		)
		(duplicate_pad_numbers_are_jumpers no)
		(fp_line
			(start -1.2954 0.5842)
			(end -1.2954 -0.5842)
			(stroke
				(width 0.1524)
				(type default)
			)
			(layer "F.SilkS")
		)
		(fp_line
			(start 1.2954 0.5842)
			(end -1.2954 0.5842)
			(stroke
				(width 0.1524)
				(type default)
			)
			(layer "F.SilkS")
		)
		(fp_line
			(start -1.2954 -0.5842)
			(end 1.2954 -0.5842)
			(stroke
				(width 0.1524)
				(type default)
			)
			(layer "F.SilkS")
		)
		(fp_line
			(start 1.2954 -0.5842)
			(end 1.2954 0.5842)
			(stroke
				(width 0.1524)
				(type default)
			)
			(layer "F.SilkS")
		)
		(fp_line
			(start -0.8636 0.4572)
			(end -0.8636 0.4318)
			(stroke
				(width 0.1)
				(type default)
			)
			(layer "F.Fab")
		)
		(fp_line
			(start 0.8636 0.4572)
			(end -0.8636 0.4572)
			(stroke
				(width 0.1)
				(type default)
			)
			(layer "F.Fab")
		)
		(fp_line
			(start -0.8636 0.4318)
			(end -0.8636 0.4064)
			(stroke
				(width 0.1)
				(type default)
			)
			(layer "F.Fab")
		)
		(fp_line
			(start -1.1938 0.4064)
			(end -1.1938 -0.406654)
			(stroke
				(width 0.1)
				(type default)
			)
			(layer "F.Fab")
		)
		(fp_line
			(start -0.8636 0.4064)
			(end -1.1938 0.4064)
			(stroke
				(width 0.1)
				(type default)
			)
			(layer "F.Fab")
		)
		(fp_line
			(start 0.8636 0.4064)
			(end 0.8636 0.4572)
			(stroke
				(width 0.1)
				(type default)
			)
			(layer "F.Fab")
		)
		(fp_line
			(start 1.1938 0.4064)
			(end 0.8636 0.4064)
			(stroke
				(width 0.1)
				(type default)
			)
			(layer "F.Fab")
		)
		(fp_line
			(start -1.1938 -0.406654)
			(end -0.8636 -0.406654)
			(stroke
				(width 0.1)
				(type default)
			)
			(layer "F.Fab")
		)
		(fp_line
			(start -0.8636 -0.406654)
			(end -0.8636 -0.4572)
			(stroke
				(width 0.1)
				(type default)
			)
			(layer "F.Fab")
		)
		(fp_line
			(start 0.8636 -0.406654)
			(end 1.1938 -0.406654)
			(stroke
				(width 0.1)
				(type default)
			)
			(layer "F.Fab")
		)
		(fp_line
			(start 1.1938 -0.406654)
			(end 1.1938 0.4064)
			(stroke
				(width 0.1)
				(type default)
			)
			(layer "F.Fab")
		)
		(fp_line
			(start -0.8636 -0.4572)
			(end 0.8636 -0.4572)
			(stroke
				(width 0.1)
				(type default)
			)
			(layer "F.Fab")
		)
		(fp_line
			(start 0.8636 -0.4572)
			(end 0.8636 -0.406654)
			(stroke
				(width 0.1)
				(type default)
			)
			(layer "F.Fab")
		)
		(pad "1" smd rect
			(at -0.7366 0 180)
			(size 0.7112 0.8128)
			(layers "F.Cu" "F.Mask" "F.Paste")
			(net "P52V_HS1_GATE2_R")
		)
		(pad "2" smd rect
			(at 0.7366 0 180)
			(size 0.7112 0.8128)
			(layers "F.Cu" "F.Mask" "F.Paste")
			(net "P52V_HS1_GATE5")
		)
	)
)
